(kicad_pcb
	(version 20260206)
	(generator "pcbnew")
	(generator_version "10.0")
	(general
		(thickness 1.6)
		(legacy_teardrops no)
	)
	(paper "A4")
	(title_block
		(title "Wiwynn_Tioga_Pass_MB.brd")
		(comment 1 "Tioga Pass / footprints 2009-2015 of 4770")
	)
	(layers
		(0 "F.Cu" signal "TOP")
		(4 "In1.Cu" signal "L2GND")
		(6 "In2.Cu" signal "L3")
		(8 "In3.Cu" signal "L4GND")
		(10 "In4.Cu" signal "L5")
		(12 "In5.Cu" signal "L6GND")
		(14 "In6.Cu" signal "L7VCC")
		(16 "In7.Cu" signal "L8VCC")
		(18 "In8.Cu" signal "L9GND")
		(20 "In9.Cu" signal "L10")
		(22 "In10.Cu" signal "L11GND")
		(24 "In11.Cu" signal "L12")
		(26 "In12.Cu" signal "L13GND")
		(2 "B.Cu" signal "BOTTOM")
		(9 "F.Adhes" user "F.Adhesive")
		(11 "B.Adhes" user "B.Adhesive")
		(13 "F.Paste" user "Package Geometry/Pastemask Top")
		(15 "B.Paste" user "Package Geometry/Pastemask Bottom")
		(5 "F.SilkS" user "Ref Des/Silkscreen Top")
		(7 "B.SilkS" user "Ref Des/Silkscreen Bottom")
		(1 "F.Mask" user "Board Geometry/Soldermask Top")
		(3 "B.Mask" user "Board Geometry/Soldermask Bottom")
		(17 "Dwgs.User" user "User.Drawings")
		(19 "Cmts.User" user "User.Comments")
		(21 "Eco1.User" user "User.Eco1")
		(23 "Eco2.User" user "User.Eco2")
		(25 "Edge.Cuts" user "Board Geometry/Outline")
		(27 "Margin" user)
		(31 "F.CrtYd" user "Package Geometry/Place Bound Top")
		(29 "B.CrtYd" user "Package Geometry/Place Bound Bottom")
		(35 "F.Fab" user "Ref Des/Assembly Top")
		(33 "B.Fab" user "Ref Des/Assembly Bottom")
	)
	(footprint ""
		(layer "F.Cu")
		(at 343.95664 -2.44348 90)
		(property "Reference" "RT35"
			(at 0 0 90)
			(layer "F.SilkS")
			(hide yes)
			(effects
				(font
					(size 1.27 1.27)
				)
			)
		)
		(property "Value" "*"
			(at -0.0254 -2.6289 90)
			(unlocked yes)
			(layer "F.Fab")
			(hide yes)
			(effects
				(font
					(size 1.27 1.016)
					(thickness 0.1524)
				)
			)
		)
		(property "Device Type" "1R3F-GP_RCL_GP-1R3F-GP,64.1R00A"
			(at -0.0254 -4.1529 90)
			(unlocked yes)
			(layer "F.Fab")
			(hide yes)
			(effects
				(font
					(size 1.27 1.016)
					(thickness 0.1524)
				)
			)
		)
		(duplicate_pad_numbers_are_jumpers no)
		(fp_line
			(start 0.2032 0)
			(end 0.4826 0)
			(stroke
				(width 0.2032)
				(type default)
			)
			(layer "F.SilkS")
		)
		(fp_line
			(start -0.4826 0)
			(end -0.2032 0)
			(stroke
				(width 0.2032)
				(type default)
			)
			(layer "F.SilkS")
		)
		(fp_rect
			(start -0.5842 1.3335)
			(end 0.5842 -1.3335)
			(stroke
				(width 0)
				(type default)
			)
			(fill no)
			(layer "F.CrtYd")
		)
		(fp_rect
			(start -0.5842 1.3335)
			(end 0.5842 -1.3335)
			(stroke
				(width 0)
				(type default)
			)
			(fill no)
			(layer "F.Fab")
		)
		(pad "1" smd custom
			(at 0 -0.762 90)
			(size 0.2159 0.2159)
			(layers "F.Cu" "F.Mask" "F.Paste")
			(net "VR_PVDDQ_ABC_PH2_SW_RC")
			(options
				(clearance outline)
				(anchor circle)
			)
			(primitives
				(gr_poly
					(pts
						(arc
							(start -0.3302 -0.4318)
							(mid -0.402042 -0.402042)
							(end -0.4318 -0.3302)
						)
						(arc
							(start -0.4318 0.3302)
							(mid -0.402042 0.402042)
							(end -0.3302 0.4318)
						)
						(arc
							(start 0.3302 0.4318)
							(mid 0.402042 0.402042)
							(end 0.4318 0.3302)
						)
						(arc
							(start 0.4318 -0.3302)
							(mid 0.402042 -0.402042)
							(end 0.3302 -0.4318)
						)
					)
					(width 0)
					(fill yes)
				)
			)
		)
		(pad "2" smd custom
			(at 0 0.762 90)
			(size 0.2159 0.2159)
			(layers "F.Cu" "F.Mask" "F.Paste")
			(net "GND")
			(options
				(clearance outline)
				(anchor circle)
			)
			(primitives
				(gr_poly
					(pts
						(arc
							(start -0.3302 -0.4318)
							(mid -0.402042 -0.402042)
							(end -0.4318 -0.3302)
						)
						(arc
							(start -0.4318 0.3302)
							(mid -0.402042 0.402042)
							(end -0.3302 0.4318)
						)
						(arc
							(start 0.3302 0.4318)
							(mid 0.402042 0.402042)
							(end 0.4318 0.3302)
						)
						(arc
							(start 0.4318 -0.3302)
							(mid 0.402042 -0.402042)
							(end 0.3302 -0.4318)
						)
					)
					(width 0)
					(fill yes)
				)
			)
		)
	)
	(footprint ""
		(layer "F.Cu")
		(at 194.344036 -69.770244)
		(property "Reference" "CT39"
			(at -0.35687 -5.5118 270)
			(unlocked yes)
			(layer "F.SilkS")
			(effects
				(font
					(size 0.7874 0.5842)
					(thickness 0.1524)
				)
				(justify left)
			)
		)
		(property "Value" ""
			(at 0 0 0)
			(layer "F.Fab")
			(effects
				(font
					(size 1.27 1.27)
				)
			)
		)
		(duplicate_pad_numbers_are_jumpers no)
		(fp_poly
			(pts
				(xy 0.3048 -0.1016) (xy 0.3048 0.9906) (xy -0.3048 0.9906) (xy -0.3048 -0.1016)
			)
			(stroke
				(width 0)
				(type default)
			)
			(fill no)
			(layer "F.CrtYd")
		)
		(fp_line
			(start -0.3048 -0.1016)
			(end -0.3048 0.9906)
			(stroke
				(width 0.1)
				(type default)
			)
			(layer "F.Fab")
		)
		(fp_line
			(start -0.3048 0.9906)
			(end 0.3048 0.9906)
			(stroke
				(width 0.1)
				(type default)
			)
			(layer "F.Fab")
		)
		(fp_line
			(start 0.3048 -0.1016)
			(end -0.3048 -0.1016)
			(stroke
				(width 0.1)
				(type default)
			)
			(layer "F.Fab")
		)
		(fp_line
			(start 0.3048 0.9906)
			(end 0.3048 -0.1016)
			(stroke
				(width 0.1)
				(type default)
			)
			(layer "F.Fab")
		)
		(pad "1" smd rect
			(at 0 0)
			(size 0.508 0.508)
			(layers "F.Cu" "F.Mask" "F.Paste")
			(net "VR_PVCCIN_CPU0_AIREF3")
		)
		(pad "2" smd rect
			(at 0 0.889)
			(size 0.508 0.508)
			(layers "F.Cu" "F.Mask" "F.Paste")
			(net "GND")
		)
		(zone
			(layer "F.Cu")
			(hatch none 0.5)
			(connect_pads
				(clearance 0)
			)
			(min_thickness 0.25)
			(keepout
				(tracks allowed)
				(vias not_allowed)
				(pads allowed)
				(copperpour not_allowed)
				(footprints allowed)
			)
			(placement
				(enabled no)
				(sheetname "")
			)
			(fill
				(thermal_gap 0.5)
				(thermal_bridge_width 0.5)
				(island_removal_mode 0)
			)
			(polygon
				(pts
					(xy 194.090036 -69.516244) (xy 194.598036 -69.516244) (xy 194.598036 -69.135244) (xy 194.090036 -69.135244)
				)
			)
		)
		(zone
			(layer "F.Cu")
			(hatch none 0.5)
			(connect_pads
				(clearance 0)
			)
			(min_thickness 0.25)
			(keepout
				(tracks not_allowed)
				(vias allowed)
				(pads allowed)
				(copperpour not_allowed)
				(footprints allowed)
			)
			(placement
				(enabled no)
				(sheetname "")
			)
			(fill
				(thermal_gap 0.5)
				(thermal_bridge_width 0.5)
				(island_removal_mode 0)
			)
			(polygon
				(pts
					(xy 194.090036 -69.135244) (xy 194.598036 -69.135244) (xy 194.598036 -69.516244) (xy 194.090036 -69.516244)
				)
			)
		)
	)
	(footprint ""
		(layer "F.Cu")
		(at 107.8611 -140.208 90)
		(property "Reference" "C3A5"
			(at 1.848866 0.752348 90)
			(unlocked yes)
			(layer "F.SilkS")
			(effects
				(font
					(size 1.27 0.9652)
					(thickness 0.1524)
				)
			)
		)
		(property "Value" ""
			(at 0 0 90)
			(layer "F.Fab")
			(effects
				(font
					(size 1.27 1.27)
				)
			)
		)
		(duplicate_pad_numbers_are_jumpers no)
		(fp_rect
			(start -0.500126 1.598422)
			(end 0.500126 -0.201422)
			(stroke
				(width 0)
				(type default)
			)
			(fill no)
			(layer "F.CrtYd")
		)
		(fp_line
			(start 0.500126 -0.201422)
			(end 0.500126 1.598422)
			(stroke
				(width 0.1)
				(type default)
			)
			(layer "F.Fab")
		)
		(fp_line
			(start -0.500126 -0.201422)
			(end 0.500126 -0.201422)
			(stroke
				(width 0.1)
				(type default)
			)
			(layer "F.Fab")
		)
		(fp_line
			(start 0.500126 1.598422)
			(end -0.500126 1.598422)
			(stroke
				(width 0.1)
				(type default)
			)
			(layer "F.Fab")
		)
		(fp_line
			(start -0.500126 1.598422)
			(end -0.500126 -0.201422)
			(stroke
				(width 0.1)
				(type default)
			)
			(layer "F.Fab")
		)
		(pad "1" smd rect
			(at 0 0)
			(size 0.889 0.9906)
			(layers "F.Cu" "F.Mask" "F.Paste")
			(net "PVDDQ_KLM")
		)
		(pad "2" smd rect
			(at 0 1.397)
			(size 0.889 0.9906)
			(layers "F.Cu" "F.Mask" "F.Paste")
			(net "GND")
		)
		(zone
			(layer "F.Cu")
			(hatch none 0.5)
			(connect_pads
				(clearance 0)
			)
			(min_thickness 0.25)
			(keepout
				(tracks allowed)
				(vias not_allowed)
				(pads allowed)
				(copperpour not_allowed)
				(footprints allowed)
			)
			(placement
				(enabled no)
				(sheetname "")
			)
			(fill
				(thermal_gap 0.5)
				(thermal_bridge_width 0.5)
				(island_removal_mode 0)
			)
			(polygon
				(pts
					(xy 108.8136 -139.7127) (xy 108.8136 -140.7033) (xy 108.3056 -140.7033) (xy 108.3056 -139.7127)
				)
			)
		)
		(zone
			(layer "F.Cu")
			(hatch none 0.5)
			(connect_pads
				(clearance 0)
			)
			(min_thickness 0.25)
			(keepout
				(tracks not_allowed)
				(vias allowed)
				(pads allowed)
				(copperpour not_allowed)
				(footprints allowed)
			)
			(placement
				(enabled no)
				(sheetname "")
			)
			(fill
				(thermal_gap 0.5)
				(thermal_bridge_width 0.5)
				(island_removal_mode 0)
			)
			(polygon
				(pts
					(xy 108.8136 -139.7127) (xy 108.8136 -140.7033) (xy 108.3056 -140.7033) (xy 108.3056 -139.7127)
				)
			)
		)
	)
	(footprint ""
		(layer "F.Cu")
		(at 364.617 -115.189 90)
		(property "Reference" "C7B25"
			(at 0 0 90)
			(layer "F.SilkS")
			(hide yes)
			(effects
				(font
					(size 1.27 1.27)
				)
			)
		)
		(property "Value" ""
			(at 0 0 90)
			(layer "F.Fab")
			(effects
				(font
					(size 1.27 1.27)
				)
			)
		)
		(duplicate_pad_numbers_are_jumpers no)
		(fp_poly
			(pts
				(xy 0.3048 -0.1016) (xy 0.3048 0.9906) (xy -0.3048 0.9906) (xy -0.3048 -0.1016)
			)
			(stroke
				(width 0)
				(type default)
			)
			(fill no)
			(layer "F.CrtYd")
		)
		(fp_line
			(start 0.3048 -0.1016)
			(end -0.3048 -0.1016)
			(stroke
				(width 0.1)
				(type default)
			)
			(layer "F.Fab")
		)
		(fp_line
			(start -0.3048 -0.1016)
			(end -0.3048 0.9906)
			(stroke
				(width 0.1)
				(type default)
			)
			(layer "F.Fab")
		)
		(fp_line
			(start 0.3048 0.9906)
			(end 0.3048 -0.1016)
			(stroke
				(width 0.1)
				(type default)
			)
			(layer "F.Fab")
		)
		(fp_line
			(start -0.3048 0.9906)
			(end 0.3048 0.9906)
			(stroke
				(width 0.1)
				(type default)
			)
			(layer "F.Fab")
		)
		(pad "1" smd rect
			(at 0 0 90)
			(size 0.508 0.508)
			(layers "F.Cu" "F.Mask" "F.Paste")
			(net "DMI_CPU0_PCH_TX_DP<3>")
		)
		(pad "2" smd rect
			(at 0 0.889 90)
			(size 0.508 0.508)
			(layers "F.Cu" "F.Mask" "F.Paste")
			(net "DMI_CPU0_PCH_TX_C_DP<3>")
		)
		(zone
			(layer "F.Cu")
			(hatch none 0.5)
			(connect_pads
				(clearance 0)
			)
			(min_thickness 0.25)
			(keepout
				(tracks allowed)
				(vias not_allowed)
				(pads allowed)
				(copperpour not_allowed)
				(footprints allowed)
			)
			(placement
				(enabled no)
				(sheetname "")
			)
			(fill
				(thermal_gap 0.5)
				(thermal_bridge_width 0.5)
				(island_removal_mode 0)
			)
			(polygon
				(pts
					(xy 364.871 -114.935) (xy 364.871 -115.443) (xy 365.252 -115.443) (xy 365.252 -114.935)
				)
			)
		)
		(zone
			(layer "F.Cu")
			(hatch none 0.5)
			(connect_pads
				(clearance 0)
			)
			(min_thickness 0.25)
			(keepout
				(tracks not_allowed)
				(vias allowed)
				(pads allowed)
				(copperpour not_allowed)
				(footprints allowed)
			)
			(placement
				(enabled no)
				(sheetname "")
			)
			(fill
				(thermal_gap 0.5)
				(thermal_bridge_width 0.5)
				(island_removal_mode 0)
			)
			(polygon
				(pts
					(xy 365.252 -114.935) (xy 365.252 -115.443) (xy 364.871 -115.443) (xy 364.871 -114.935)
				)
			)
		)
	)
	(footprint ""
		(layer "F.Cu")
		(at 181.890924 -148.3487 90)
		(property "Reference" "EU4A1"
			(at -0.2667 3.555746 90)
			(unlocked yes)
			(layer "F.SilkS")
			(effects
				(font
					(size 0.7874 0.5842)
					(thickness 0.1524)
				)
				(justify left)
			)
		)
		(property "Value" ""
			(at 0 0 90)
			(layer "F.Fab")
			(effects
				(font
					(size 1.27 1.27)
				)
			)
		)
		(duplicate_pad_numbers_are_jumpers no)
		(fp_circle
			(center -0.835152 -0.417322)
			(end -0.835152 -0.290576)
			(stroke
				(width 0.254)
				(type default)
			)
			(fill no)
			(layer "F.SilkS")
		)
		(fp_poly
			(pts
				(xy -0.064516 -1.0922) (xy -0.064516 -0.3302) (xy 0.697484 -1.0922)
			)
			(stroke
				(width 0)
				(type default)
			)
			(fill yes)
			(layer "F.SilkS")
		)
		(fp_rect
			(start 0.597408 2.295398)
			(end 2.273808 -0.295402)
			(stroke
				(width 0)
				(type default)
			)
			(fill yes)
			(layer "F.Paste")
		)
		(fp_rect
			(start -0.064516 2.500122)
			(end 2.935478 -0.500126)
			(stroke
				(width 0)
				(type default)
			)
			(fill no)
			(layer "F.CrtYd")
		)
		(fp_line
			(start 2.935478 -0.500126)
			(end 2.935478 2.500122)
			(stroke
				(width 0.1)
				(type default)
			)
			(layer "F.Fab")
		)
		(fp_line
			(start -0.064516 -0.500126)
			(end 2.935478 -0.500126)
			(stroke
				(width 0.1)
				(type default)
			)
			(layer "F.Fab")
		)
		(fp_line
			(start 2.935478 2.500122)
			(end -0.064516 2.500122)
			(stroke
				(width 0.1)
				(type default)
			)
			(layer "F.Fab")
		)
		(fp_line
			(start -0.064516 2.500122)
			(end -0.064516 -0.500126)
			(stroke
				(width 0.1)
				(type default)
			)
			(layer "F.Fab")
		)
		(fp_circle
			(center -0.835152 -0.417322)
			(end -0.835152 -0.290576)
			(stroke
				(width 0.254)
				(type default)
			)
			(fill no)
			(layer "F.Fab")
		)
		(pad "1" smd rect
			(at 0 0 90)
			(size 0.6858 0.3048)
			(layers "F.Cu" "F.Mask" "F.Paste")
			(net "VR_PVTT_DEF_VREF")
		)
		(pad "2" smd rect
			(at 0 0.500126 90)
			(size 0.6858 0.3048)
			(layers "F.Cu" "F.Mask" "F.Paste")
			(net "VR_PVTT_DEF_BIAS")
		)
		(pad "3" smd rect
			(at 0 0.999998 90)
			(size 0.6858 0.3048)
			(layers "F.Cu" "F.Mask" "F.Paste")
			(net "GND")
		)
		(pad "4" smd rect
			(at 0 1.500124 90)
			(size 0.6858 0.3048)
			(layers "F.Cu" "F.Mask" "F.Paste")
			(net "VSENSE_PVDDQ_DEF_VTT")
		)
		(pad "5" smd rect
			(at 0 1.999996 90)
			(size 0.6858 0.3048)
			(layers "F.Cu" "F.Mask" "F.Paste")
			(net "PWRGD_PVTT_DEF_CPU0_R")
		)
		(pad "6" smd rect
			(at 2.871216 1.999996 90)
			(size 0.6858 0.3048)
			(layers "F.Cu" "F.Mask" "F.Paste")
			(net "VR_PVTT_DEF_SNS")
		)
		(pad "7" smd rect
			(at 2.871216 1.500124 90)
			(size 0.6858 0.3048)
			(layers "F.Cu" "F.Mask" "F.Paste")
			(net "FM_PVTT_DEF_EN_R")
		)
		(pad "8" smd rect
			(at 2.871216 0.999998 90)
			(size 0.6858 0.3048)
			(layers "F.Cu" "F.Mask" "F.Paste")
			(net "GND")
		)
		(pad "9" smd rect
			(at 2.871216 0.500126 90)
			(size 0.6858 0.3048)
			(layers "F.Cu" "F.Mask" "F.Paste")
			(net "PVTT_DEF")
		)
		(pad "10" smd rect
			(at 2.871216 0 90)
			(size 0.6858 0.3048)
			(layers "F.Cu" "F.Mask" "F.Paste")
			(net "PVDDQ_DEF")
		)
		(pad "11" smd rect
			(at 1.435608 0.999998 90)
			(size 1.6764 2.5908)
			(layers "F.Cu" "F.Mask" "F.Paste")
			(net "GND")
		)
	)
	(footprint ""
		(layer "F.Cu")
		(at 277.182834 -77.382116)
		(property "Reference" "C6D5"
			(at 0 0 0)
			(layer "F.SilkS")
			(hide yes)
			(effects
				(font
					(size 1.27 1.27)
				)
			)
		)
		(property "Value" ""
			(at 0 0 0)
			(layer "F.Fab")
			(effects
				(font
					(size 1.27 1.27)
				)
			)
		)
		(duplicate_pad_numbers_are_jumpers no)
		(fp_poly
			(pts
				(xy -0.4953 -0.2032) (xy 0.4953 -0.2032) (xy 0.4953 1.6002) (xy -0.4953 1.6002)
			)
			(stroke
				(width 0)
				(type default)
			)
			(fill no)
			(layer "F.CrtYd")
		)
		(fp_line
			(start -0.4953 -0.2032)
			(end 0.4953 -0.2032)
			(stroke
				(width 0.1)
				(type default)
			)
			(layer "F.Fab")
		)
		(fp_line
			(start -0.4953 1.6002)
			(end -0.4953 -0.2032)
			(stroke
				(width 0.1)
				(type default)
			)
			(layer "F.Fab")
		)
		(fp_line
			(start 0.4953 -0.2032)
			(end 0.4953 1.6002)
			(stroke
				(width 0.1)
				(type default)
			)
			(layer "F.Fab")
		)
		(fp_line
			(start 0.4953 1.6002)
			(end -0.4953 1.6002)
			(stroke
				(width 0.1)
				(type default)
			)
			(layer "F.Fab")
		)
		(pad "1" smd rect
			(at 0 0)
			(size 0.762 0.889)
			(layers "F.Cu" "F.Mask" "F.Paste")
			(net "PVCCMCP_CPU0")
		)
		(pad "2" smd rect
			(at 0 1.397)
			(size 0.762 0.889)
			(layers "F.Cu" "F.Mask" "F.Paste")
			(net "GND")
		)
		(zone
			(layer "F.Cu")
			(hatch none 0.5)
			(connect_pads
				(clearance 0)
			)
			(min_thickness 0.25)
			(keepout
				(tracks not_allowed)
				(vias allowed)
				(pads allowed)
				(copperpour not_allowed)
				(footprints allowed)
			)
			(placement
				(enabled no)
				(sheetname "")
			)
			(fill
				(thermal_gap 0.5)
				(thermal_bridge_width 0.5)
				(island_removal_mode 0)
			)
			(polygon
				(pts
					(xy 276.801834 -76.937616) (xy 277.563834 -76.937616) (xy 277.563834 -76.429616) (xy 276.801834 -76.429616)
				)
			)
		)
	)
	(footprint ""
		(layer "F.Cu")
		(at 27.785568 -13.3985)
		(property "Reference" "R1G1"
			(at 0 0 0)
			(layer "F.SilkS")
			(hide yes)
			(effects
				(font
					(size 1.27 1.27)
				)
			)
		)
		(property "Value" ""
			(at 0 0 0)
			(layer "F.Fab")
			(effects
				(font
					(size 1.27 1.27)
				)
			)
		)
		(duplicate_pad_numbers_are_jumpers no)
		(fp_poly
			(pts
				(xy -0.2794 -0.1016) (xy 0.2794 -0.1016) (xy 0.2794 0.9906) (xy -0.2794 0.9906)
			)
			(stroke
				(width 0)
				(type default)
			)
			(fill no)
			(layer "F.CrtYd")
		)
		(fp_line
			(start -0.2794 -0.1016)
			(end -0.2794 0.9906)
			(stroke
				(width 0.1)
				(type default)
			)
			(layer "F.Fab")
		)
		(fp_line
			(start -0.2794 0.9906)
			(end 0.2794 0.9906)
			(stroke
				(width 0.1)
				(type default)
			)
			(layer "F.Fab")
		)
		(fp_line
			(start 0.2794 -0.1016)
			(end -0.2794 -0.1016)
			(stroke
				(width 0.1)
				(type default)
			)
			(layer "F.Fab")
		)
		(fp_line
			(start 0.2794 0.9906)
			(end 0.2794 -0.1016)
			(stroke
				(width 0.1)
				(type default)
			)
			(layer "F.Fab")
		)
		(pad "1" smd rect
			(at 0 0)
			(size 0.508 0.508)
			(layers "F.Cu" "F.Mask" "F.Paste")
			(net "M_H_CPU_VREF")
		)
		(pad "2" smd rect
			(at 0 0.889)
			(size 0.508 0.508)
			(layers "F.Cu" "F.Mask" "F.Paste")
			(net "M_H_VREF")
		)
		(zone
			(layer "F.Cu")
			(hatch none 0.5)
			(connect_pads
				(clearance 0)
			)
			(min_thickness 0.25)
			(keepout
				(tracks allowed)
				(vias not_allowed)
				(pads allowed)
				(copperpour not_allowed)
				(footprints allowed)
			)
			(placement
				(enabled no)
				(sheetname "")
			)
			(fill
				(thermal_gap 0.5)
				(thermal_bridge_width 0.5)
				(island_removal_mode 0)
			)
			(polygon
				(pts
					(xy 27.531568 -13.1445) (xy 28.039568 -13.1445) (xy 28.039568 -12.7635) (xy 27.531568 -12.7635)
				)
			)
		)
		(zone
			(layer "F.Cu")
			(hatch none 0.5)
			(connect_pads
				(clearance 0)
			)
			(min_thickness 0.25)
			(keepout
				(tracks not_allowed)
				(vias allowed)
				(pads allowed)
				(copperpour not_allowed)
				(footprints allowed)
			)
			(placement
				(enabled no)
				(sheetname "")
			)
			(fill
				(thermal_gap 0.5)
				(thermal_bridge_width 0.5)
				(island_removal_mode 0)
			)
			(polygon
				(pts
					(xy 27.531568 -12.7635) (xy 28.039568 -12.7635) (xy 28.039568 -13.1445) (xy 27.531568 -13.1445)
				)
			)
		)
	)
)
